FILE_TYPE = CONNECTIVITY;
{Allegro Design Entry HDL 17.2-2016 S081 (4005846) 1/11/2022}
"PAGE_NUMBER" = 26;
0"NC";
1"WAFL_CPU1_TX1_CPU0_RX0_DN"$PHYS_NET_NAME"P3E_M2_0_SATA_RX_DP";
2"WAFL_CPU1_TX1_CPU0_RX0_DP";
3"WAFL_CPU0_TX0_CPU1_RX1_DN"$PHYS_NET_NAME"P3E_M2_0_SATA_RX_DP";
4"WAFL_CPU0_TX0_CPU1_RX1_DP";
%"GENOA_SP5"
"19","(-4575,4800)","0","pure_quanta","I59";
;
LOCATION"U25"
$SEC"19"
CDS_SEC"19"
PART_TYPE"SMLF"
MATERIAL"IO"
VALUE"SOCKET6096_13568-001"
PART_NUMBER"DGA^6000030"
CDS_LMAN_SYM_OUTLINE"-800,600,800,-600"
NEEDS_NO_SIZE"TRUE"
CDS_LIB"pure_quanta";
"WAFL_TXP1||P5_TXP1"
$PN"C47"0;
"WAFL_TXN1||P5_TXN1"
$PN"C48"0;
"WAFL_TXP0||P5_TXP0"
$PN"C50"4;
"WAFL_TXN0||P5_TXN0"
$PN"C51"3;
"WAFL_RXP1||P5_RXP1"
$PN"E46"0;
"WAFL_RXN1||P5_RXN1"
$PN"E47"0;
"WAFL_RXP0||P5_RXP0"
$PN"E49"2;
"WAFL_RXN0||P5_RXN0"
$PN"E50"1;
"P4_RXN1"
$PN"DG50"0;
"P4_RXN0"
$PN"DG53"0;
"P4_RXP1"
$PN"DG51"0;
"P4_TXN1"
$PN"DE49"0;
"P4_RXP0"
$PN"DG54"0;
"P4_TXN0"
$PN"DE52"0;
"P4_TXP1"
$PN"DE50"0;
"P4_TXP0"
$PN"DE53"0;
"P5_TXP3"
$PN"C41"0;
"P5_TXP2"
$PN"C44"0;
"P5_TXN3"
$PN"C42"0;
"P5_TXN2"
$PN"C45"0;
"P5_RXP3"
$PN"E40"0;
"P5_RXP2"
$PN"E43"0;
"P5_RXN3"
$PN"E41"0;
"P5_RXN2"
$PN"E44"0;
"P4_TXP3"
$PN"DE44"0;
"P4_TXP2"
$PN"DE47"0;
"P4_TXN3"
$PN"DE43"0;
"P4_TXN2"
$PN"DE46"0;
"P4_RXP3"
$PN"DG45"0;
"P4_RXP2"
$PN"DG48"0;
"P4_RXN3"
$PN"DG44"0;
"P4_RXN2"
$PN"DG47"0;
END.
